(kicad_pcb
	(version 20260206)
	(generator "pcbnew")
	(generator_version "10.0")
	(general
		(thickness 1.6)
		(legacy_teardrops no)
	)
	(paper "A4")
	(title_block
		(title "9054_F0T_PDB_BD_GPU_F_V04_1213_1550_OCP.brd")
		(comment 1 "Grand Teton / footprints 325-331 of 608")
	)
	(layers
		(0 "F.Cu" signal "TOP")
		(4 "In1.Cu" signal "GND")
		(6 "In2.Cu" signal "IN1")
		(8 "In3.Cu" signal "GND1")
		(10 "In4.Cu" signal "VCC")
		(12 "In5.Cu" signal "VCC1")
		(14 "In6.Cu" signal "GND2")
		(16 "In7.Cu" signal "IN2")
		(18 "In8.Cu" signal "GND3")
		(2 "B.Cu" signal "BOTTOM")
		(9 "F.Adhes" user "F.Adhesive")
		(11 "B.Adhes" user "B.Adhesive")
		(13 "F.Paste" user "Package Geometry/Pastemask Top")
		(15 "B.Paste" user "Package Geometry/Pastemask Bottom")
		(5 "F.SilkS" user "Ref Des/Silkscreen Top")
		(7 "B.SilkS" user "Ref Des/Silkscreen Bottom")
		(1 "F.Mask" user "Board Geometry/Soldermask Top")
		(3 "B.Mask" user "Board Geometry/Soldermask Bottom")
		(17 "Dwgs.User" user "User.Drawings")
		(19 "Cmts.User" user "User.Comments")
		(21 "Eco1.User" user "User.Eco1")
		(23 "Eco2.User" user "User.Eco2")
		(25 "Edge.Cuts" user "Board Geometry/Outline")
		(27 "Margin" user)
		(31 "F.CrtYd" user "Package Geometry/Place Bound Top")
		(29 "B.CrtYd" user "Package Geometry/Place Bound Bottom")
		(35 "F.Fab" user "Ref Des/Assembly Top")
		(33 "B.Fab" user "Ref Des/Assembly Bottom")
	)
	(footprint ""
		(layer "F.Cu")
		(at 302.4124 -69.977 180)
		(property "Reference" "PR6960"
			(at 0 0 180)
			(layer "F.SilkS")
			(hide yes)
			(effects
				(font
					(size 1.27 1.27)
				)
			)
		)
		(property "Value" ""
			(at 0 0 180)
			(layer "F.Fab")
			(effects
				(font
					(size 1.27 1.27)
				)
			)
		)
		(duplicate_pad_numbers_are_jumpers no)
		(fp_line
			(start 1.2954 0.5842)
			(end -1.2954 0.5842)
			(stroke
				(width 0.1524)
				(type default)
			)
			(layer "F.SilkS")
		)
		(fp_line
			(start 1.2954 -0.5842)
			(end 1.2954 0.5842)
			(stroke
				(width 0.1524)
				(type default)
			)
			(layer "F.SilkS")
		)
		(fp_line
			(start -1.2954 0.5842)
			(end -1.2954 -0.5842)
			(stroke
				(width 0.1524)
				(type default)
			)
			(layer "F.SilkS")
		)
		(fp_line
			(start -1.2954 -0.5842)
			(end 1.2954 -0.5842)
			(stroke
				(width 0.1524)
				(type default)
			)
			(layer "F.SilkS")
		)
		(fp_line
			(start 1.1938 0.4064)
			(end 0.8636 0.4064)
			(stroke
				(width 0.1)
				(type default)
			)
			(layer "F.Fab")
		)
		(fp_line
			(start 1.1938 -0.406654)
			(end 1.1938 0.4064)
			(stroke
				(width 0.1)
				(type default)
			)
			(layer "F.Fab")
		)
		(fp_line
			(start 0.8636 0.4572)
			(end -0.8636 0.4572)
			(stroke
				(width 0.1)
				(type default)
			)
			(layer "F.Fab")
		)
		(fp_line
			(start 0.8636 0.4064)
			(end 0.8636 0.4572)
			(stroke
				(width 0.1)
				(type default)
			)
			(layer "F.Fab")
		)
		(fp_line
			(start 0.8636 -0.406654)
			(end 1.1938 -0.406654)
			(stroke
				(width 0.1)
				(type default)
			)
			(layer "F.Fab")
		)
		(fp_line
			(start 0.8636 -0.4572)
			(end 0.8636 -0.406654)
			(stroke
				(width 0.1)
				(type default)
			)
			(layer "F.Fab")
		)
		(fp_line
			(start -0.8636 0.4572)
			(end -0.8636 0.4318)
			(stroke
				(width 0.1)
				(type default)
			)
			(layer "F.Fab")
		)
		(fp_line
			(start -0.8636 0.4318)
			(end -0.8636 0.4064)
			(stroke
				(width 0.1)
				(type default)
			)
			(layer "F.Fab")
		)
		(fp_line
			(start -0.8636 0.4064)
			(end -1.1938 0.4064)
			(stroke
				(width 0.1)
				(type default)
			)
			(layer "F.Fab")
		)
		(fp_line
			(start -0.8636 -0.406654)
			(end -0.8636 -0.4572)
			(stroke
				(width 0.1)
				(type default)
			)
			(layer "F.Fab")
		)
		(fp_line
			(start -0.8636 -0.4572)
			(end 0.8636 -0.4572)
			(stroke
				(width 0.1)
				(type default)
			)
			(layer "F.Fab")
		)
		(fp_line
			(start -1.1938 0.4064)
			(end -1.1938 -0.406654)
			(stroke
				(width 0.1)
				(type default)
			)
			(layer "F.Fab")
		)
		(fp_line
			(start -1.1938 -0.406654)
			(end -0.8636 -0.406654)
			(stroke
				(width 0.1)
				(type default)
			)
			(layer "F.Fab")
		)
		(pad "1" smd rect
			(at -0.7366 0 90)
			(size 0.7112 0.8128)
			(layers "F.Cu" "F.Mask" "F.Paste")
			(net "P52V_HS_1272_S_P")
		)
		(pad "2" smd rect
			(at 0.7366 0 90)
			(size 0.7112 0.8128)
			(layers "F.Cu" "F.Mask" "F.Paste")
			(net "P52V_HS1_SENSE_P_R1")
		)
	)
	(footprint ""
		(layer "F.Cu")
		(at 14.99997 -60.099956)
		(property "Reference" "H22"
			(at -1.02997 -8.961374 0)
			(unlocked yes)
			(layer "F.SilkS")
			(effects
				(font
					(size 0.7874 0.5842)
					(thickness 0.1524)
				)
				(justify left)
			)
		)
		(property "Value" ""
			(at 0 0 0)
			(layer "F.Fab")
			(effects
				(font
					(size 1.27 1.27)
				)
			)
		)
		(duplicate_pad_numbers_are_jumpers no)
		(fp_circle
			(center 0 0)
			(end 7.999984 0)
			(stroke
				(width 0.1524)
				(type default)
			)
			(fill no)
			(layer "F.SilkS")
		)
		(fp_circle
			(center 0 0)
			(end 7.999984 0)
			(stroke
				(width 0.1524)
				(type default)
			)
			(fill no)
			(layer "B.SilkS")
		)
		(fp_circle
			(center 0 0)
			(end 7.999984 0)
			(stroke
				(width 0.1)
				(type default)
			)
			(fill no)
			(layer "B.Fab")
		)
		(fp_circle
			(center 0 0)
			(end 7.999984 0)
			(stroke
				(width 0.1)
				(type default)
			)
			(fill no)
			(layer "F.Fab")
		)
		(pad "" np_thru_hole circle
			(at 0 0)
			(size 4.0132 4.0132)
			(drill 4.0132)
			(layers "*.Cu" "*.Mask")
			(clearance 0.381)
			(thermal_gap 0.381)
		)
		(pad "2" thru_hole circle
			(at 0 -3.50012)
			(size 0.762 0.762)
			(drill 0.5588)
			(layers "*.Cu" "*.Mask")
			(remove_unused_layers no)
			(net "GND")
			(clearance 0.1524)
			(thermal_gap 0.1524)
		)
		(pad "3" thru_hole circle
			(at -2.500122 -2.500122)
			(size 0.762 0.762)
			(drill 0.5588)
			(layers "*.Cu" "*.Mask")
			(remove_unused_layers no)
			(net "GND")
			(clearance 0.1524)
			(thermal_gap 0.1524)
		)
		(pad "4" thru_hole circle
			(at -3.50012 0)
			(size 0.762 0.762)
			(drill 0.5588)
			(layers "*.Cu" "*.Mask")
			(remove_unused_layers no)
			(net "GND")
			(clearance 0.1524)
			(thermal_gap 0.1524)
		)
		(pad "5" thru_hole circle
			(at -2.500122 2.500122)
			(size 0.762 0.762)
			(drill 0.5588)
			(layers "*.Cu" "*.Mask")
			(remove_unused_layers no)
			(net "GND")
			(clearance 0.1524)
			(thermal_gap 0.1524)
		)
		(pad "6" thru_hole circle
			(at 0 3.50012)
			(size 0.762 0.762)
			(drill 0.5588)
			(layers "*.Cu" "*.Mask")
			(remove_unused_layers no)
			(net "GND")
			(clearance 0.1524)
			(thermal_gap 0.1524)
		)
		(pad "7" thru_hole circle
			(at 2.500122 2.500122)
			(size 0.762 0.762)
			(drill 0.5588)
			(layers "*.Cu" "*.Mask")
			(remove_unused_layers no)
			(net "GND")
			(clearance 0.1524)
			(thermal_gap 0.1524)
		)
		(pad "8" thru_hole circle
			(at 3.50012 0)
			(size 0.762 0.762)
			(drill 0.5588)
			(layers "*.Cu" "*.Mask")
			(remove_unused_layers no)
			(net "GND")
			(clearance 0.1524)
			(thermal_gap 0.1524)
		)
		(pad "9" thru_hole circle
			(at 2.500122 -2.500122)
			(size 0.762 0.762)
			(drill 0.5588)
			(layers "*.Cu" "*.Mask")
			(remove_unused_layers no)
			(net "GND")
			(clearance 0.1524)
			(thermal_gap 0.1524)
		)
		(zone
			(layers "F.Cu" "B.Cu" "In1.Cu" "In2.Cu" "In3.Cu" "In4.Cu" "In5.Cu" "In6.Cu"
				"In7.Cu" "In8.Cu"
			)
			(hatch none 0.5)
			(connect_pads
				(clearance 0)
			)
			(min_thickness 0.25)
			(keepout
				(tracks not_allowed)
				(vias allowed)
				(pads allowed)
				(copperpour not_allowed)
				(footprints allowed)
			)
			(placement
				(enabled no)
				(sheetname "")
			)
			(fill
				(thermal_gap 0.5)
				(thermal_bridge_width 0.5)
				(island_removal_mode 0)
			)
			(polygon
				(pts
					(arc
						(start 17.51457 -60.099956)
						(mid 12.48537 -60.099956)
						(end 17.51457 -60.099956)
					)
				)
			)
		)
	)
	(footprint ""
		(layer "F.Cu")
		(at 447.263266 -82.01787)
		(property "Reference" "PC60"
			(at 0 0 0)
			(layer "F.SilkS")
			(hide yes)
			(effects
				(font
					(size 1.27 1.27)
				)
			)
		)
		(property "Value" ""
			(at 0 0 0)
			(layer "F.Fab")
			(effects
				(font
					(size 1.27 1.27)
				)
			)
		)
		(duplicate_pad_numbers_are_jumpers no)
		(fp_line
			(start -0.7874 -0.4064)
			(end 0.7874 -0.4064)
			(stroke
				(width 0.1524)
				(type default)
			)
			(layer "F.SilkS")
		)
		(fp_line
			(start -0.7874 0.4064)
			(end -0.7874 -0.4064)
			(stroke
				(width 0.1524)
				(type default)
			)
			(layer "F.SilkS")
		)
		(fp_line
			(start 0.7874 -0.4064)
			(end 0.7874 0.4064)
			(stroke
				(width 0.1524)
				(type default)
			)
			(layer "F.SilkS")
		)
		(fp_line
			(start 0.7874 0.4064)
			(end -0.7874 0.4064)
			(stroke
				(width 0.1524)
				(type default)
			)
			(layer "F.SilkS")
		)
		(fp_line
			(start -0.6858 -0.3048)
			(end -0.1016 -0.3048)
			(stroke
				(width 0.1)
				(type default)
			)
			(layer "F.Fab")
		)
		(fp_line
			(start -0.6858 0.3048)
			(end -0.6858 -0.3048)
			(stroke
				(width 0.1)
				(type default)
			)
			(layer "F.Fab")
		)
		(fp_line
			(start -0.1016 -0.3048)
			(end -0.1016 -0.2794)
			(stroke
				(width 0.1)
				(type default)
			)
			(layer "F.Fab")
		)
		(fp_line
			(start -0.1016 -0.2794)
			(end 0.1016 -0.2794)
			(stroke
				(width 0.1)
				(type default)
			)
			(layer "F.Fab")
		)
		(fp_line
			(start -0.1016 0.2794)
			(end -0.1016 0.3048)
			(stroke
				(width 0.1)
				(type default)
			)
			(layer "F.Fab")
		)
		(fp_line
			(start -0.1016 0.3048)
			(end -0.6858 0.3048)
			(stroke
				(width 0.1)
				(type default)
			)
			(layer "F.Fab")
		)
		(fp_line
			(start 0.1016 -0.3048)
			(end 0.6858 -0.3048)
			(stroke
				(width 0.1)
				(type default)
			)
			(layer "F.Fab")
		)
		(fp_line
			(start 0.1016 -0.2794)
			(end 0.1016 -0.3048)
			(stroke
				(width 0.1)
				(type default)
			)
			(layer "F.Fab")
		)
		(fp_line
			(start 0.1016 0.2794)
			(end -0.1016 0.2794)
			(stroke
				(width 0.1)
				(type default)
			)
			(layer "F.Fab")
		)
		(fp_line
			(start 0.1016 0.3048)
			(end 0.1016 0.2794)
			(stroke
				(width 0.1)
				(type default)
			)
			(layer "F.Fab")
		)
		(fp_line
			(start 0.6858 -0.3048)
			(end 0.6858 0.3048)
			(stroke
				(width 0.1)
				(type default)
			)
			(layer "F.Fab")
		)
		(fp_line
			(start 0.6858 0.3048)
			(end 0.1016 0.3048)
			(stroke
				(width 0.1)
				(type default)
			)
			(layer "F.Fab")
		)
		(pad "1" smd rect
			(at -0.40005 0 180)
			(size 0.4572 0.508)
			(layers "F.Cu" "F.Mask" "F.Paste")
			(net "SW_P3V3_HPDB_FLT")
		)
		(pad "2" smd rect
			(at 0.40005 0 180)
			(size 0.4572 0.508)
			(layers "F.Cu" "F.Mask" "F.Paste")
			(net "GND")
		)
	)
	(footprint ""
		(layer "F.Cu")
		(at 406.146 -35.56)
		(property "Reference" "R42"
			(at 0 0 0)
			(layer "F.SilkS")
			(hide yes)
			(effects
				(font
					(size 1.27 1.27)
				)
			)
		)
		(property "Value" ""
			(at 0 0 0)
			(layer "F.Fab")
			(effects
				(font
					(size 1.27 1.27)
				)
			)
		)
		(duplicate_pad_numbers_are_jumpers no)
		(fp_line
			(start -2.234946 -0.9271)
			(end 2.234946 -0.9271)
			(stroke
				(width 0.1524)
				(type default)
			)
			(layer "F.SilkS")
		)
		(fp_line
			(start -2.234946 0.9271)
			(end -2.234946 -0.9271)
			(stroke
				(width 0.1524)
				(type default)
			)
			(layer "F.SilkS")
		)
		(fp_line
			(start 2.234946 -0.9271)
			(end 2.234946 0.9271)
			(stroke
				(width 0.1524)
				(type default)
			)
			(layer "F.SilkS")
		)
		(fp_line
			(start 2.234946 0.9271)
			(end -2.234946 0.9271)
			(stroke
				(width 0.1524)
				(type default)
			)
			(layer "F.SilkS")
		)
		(fp_line
			(start -1.575054 -0.824992)
			(end -1.575054 0.824992)
			(stroke
				(width 0.1)
				(type default)
			)
			(layer "F.Fab")
		)
		(fp_line
			(start -1.575054 0.824992)
			(end 1.575054 0.824992)
			(stroke
				(width 0.1)
				(type default)
			)
			(layer "F.Fab")
		)
		(fp_line
			(start 1.575054 -0.824992)
			(end -1.575054 -0.824992)
			(stroke
				(width 0.1)
				(type default)
			)
			(layer "F.Fab")
		)
		(fp_line
			(start 1.575054 0.824992)
			(end 1.575054 -0.824992)
			(stroke
				(width 0.1)
				(type default)
			)
			(layer "F.Fab")
		)
		(pad "1" smd rect
			(at -1.599946 0)
			(size 1.016 1.6002)
			(layers "F.Cu" "F.Mask" "F.Paste")
			(net "LED_D1_R2")
		)
		(pad "2" smd rect
			(at 1.599946 0)
			(size 1.016 1.6002)
			(layers "F.Cu" "F.Mask" "F.Paste")
			(net "LED_D1_R3")
		)
	)
	(footprint ""
		(layer "F.Cu")
		(at 112.988852 -21.5392 -90)
		(property "Reference" "PR6975"
			(at 0 0 270)
			(layer "F.SilkS")
			(hide yes)
			(effects
				(font
					(size 1.27 1.27)
				)
			)
		)
		(property "Value" ""
			(at 0 0 270)
			(layer "F.Fab")
			(effects
				(font
					(size 1.27 1.27)
				)
			)
		)
		(duplicate_pad_numbers_are_jumpers no)
		(fp_line
			(start -1.2954 0.5842)
			(end -1.2954 -0.5842)
			(stroke
				(width 0.1524)
				(type default)
			)
			(layer "F.SilkS")
		)
		(fp_line
			(start 1.2954 0.5842)
			(end -1.2954 0.5842)
			(stroke
				(width 0.1524)
				(type default)
			)
			(layer "F.SilkS")
		)
		(fp_line
			(start -1.2954 -0.5842)
			(end 1.2954 -0.5842)
			(stroke
				(width 0.1524)
				(type default)
			)
			(layer "F.SilkS")
		)
		(fp_line
			(start 1.2954 -0.5842)
			(end 1.2954 0.5842)
			(stroke
				(width 0.1524)
				(type default)
			)
			(layer "F.SilkS")
		)
		(fp_line
			(start -0.8636 0.4572)
			(end -0.8636 0.4318)
			(stroke
				(width 0.1)
				(type default)
			)
			(layer "F.Fab")
		)
		(fp_line
			(start 0.8636 0.4572)
			(end -0.8636 0.4572)
			(stroke
				(width 0.1)
				(type default)
			)
			(layer "F.Fab")
		)
		(fp_line
			(start -0.8636 0.4318)
			(end -0.8636 0.4064)
			(stroke
				(width 0.1)
				(type default)
			)
			(layer "F.Fab")
		)
		(fp_line
			(start -1.1938 0.4064)
			(end -1.1938 -0.406654)
			(stroke
				(width 0.1)
				(type default)
			)
			(layer "F.Fab")
		)
		(fp_line
			(start -0.8636 0.4064)
			(end -1.1938 0.4064)
			(stroke
				(width 0.1)
				(type default)
			)
			(layer "F.Fab")
		)
		(fp_line
			(start 0.8636 0.4064)
			(end 0.8636 0.4572)
			(stroke
				(width 0.1)
				(type default)
			)
			(layer "F.Fab")
		)
		(fp_line
			(start 1.1938 0.4064)
			(end 0.8636 0.4064)
			(stroke
				(width 0.1)
				(type default)
			)
			(layer "F.Fab")
		)
		(fp_line
			(start -1.1938 -0.406654)
			(end -0.8636 -0.406654)
			(stroke
				(width 0.1)
				(type default)
			)
			(layer "F.Fab")
		)
		(fp_line
			(start -0.8636 -0.406654)
			(end -0.8636 -0.4572)
			(stroke
				(width 0.1)
				(type default)
			)
			(layer "F.Fab")
		)
		(fp_line
			(start 0.8636 -0.406654)
			(end 1.1938 -0.406654)
			(stroke
				(width 0.1)
				(type default)
			)
			(layer "F.Fab")
		)
		(fp_line
			(start 1.1938 -0.406654)
			(end 1.1938 0.4064)
			(stroke
				(width 0.1)
				(type default)
			)
			(layer "F.Fab")
		)
		(fp_line
			(start -0.8636 -0.4572)
			(end 0.8636 -0.4572)
			(stroke
				(width 0.1)
				(type default)
			)
			(layer "F.Fab")
		)
		(fp_line
			(start 0.8636 -0.4572)
			(end 0.8636 -0.406654)
			(stroke
				(width 0.1)
				(type default)
			)
			(layer "F.Fab")
		)
		(pad "1" smd rect
			(at -0.7366 0 180)
			(size 0.7112 0.8128)
			(layers "F.Cu" "F.Mask" "F.Paste")
			(net "P52V_HS2_GATE2_R")
		)
		(pad "2" smd rect
			(at 0.7366 0 180)
			(size 0.7112 0.8128)
			(layers "F.Cu" "F.Mask" "F.Paste")
			(net "P52V_HS2_GATE6")
		)
	)
	(footprint ""
		(layer "F.Cu")
		(at 33.85439 -39.243)
		(property "Reference" "R41"
			(at 0 0 0)
			(layer "F.SilkS")
			(hide yes)
			(effects
				(font
					(size 1.27 1.27)
				)
			)
		)
		(property "Value" ""
			(at 0 0 0)
			(layer "F.Fab")
			(effects
				(font
					(size 1.27 1.27)
				)
			)
		)
		(duplicate_pad_numbers_are_jumpers no)
		(fp_line
			(start -2.234946 -0.9271)
			(end 2.234946 -0.9271)
			(stroke
				(width 0.1524)
				(type default)
			)
			(layer "F.SilkS")
		)
		(fp_line
			(start -2.234946 0.9271)
			(end -2.234946 -0.9271)
			(stroke
				(width 0.1524)
				(type default)
			)
			(layer "F.SilkS")
		)
		(fp_line
			(start 2.234946 -0.9271)
			(end 2.234946 0.9271)
			(stroke
				(width 0.1524)
				(type default)
			)
			(layer "F.SilkS")
		)
		(fp_line
			(start 2.234946 0.9271)
			(end -2.234946 0.9271)
			(stroke
				(width 0.1524)
				(type default)
			)
			(layer "F.SilkS")
		)
		(fp_line
			(start -1.575054 -0.824992)
			(end -1.575054 0.824992)
			(stroke
				(width 0.1)
				(type default)
			)
			(layer "F.Fab")
		)
		(fp_line
			(start -1.575054 0.824992)
			(end 1.575054 0.824992)
			(stroke
				(width 0.1)
				(type default)
			)
			(layer "F.Fab")
		)
		(fp_line
			(start 1.575054 -0.824992)
			(end -1.575054 -0.824992)
			(stroke
				(width 0.1)
				(type default)
			)
			(layer "F.Fab")
		)
		(fp_line
			(start 1.575054 0.824992)
			(end 1.575054 -0.824992)
			(stroke
				(width 0.1)
				(type default)
			)
			(layer "F.Fab")
		)
		(pad "1" smd rect
			(at -1.599946 0)
			(size 1.016 1.6002)
			(layers "F.Cu" "F.Mask" "F.Paste")
			(net "LED_D2_R1")
		)
		(pad "2" smd rect
			(at 1.599946 0)
			(size 1.016 1.6002)
			(layers "F.Cu" "F.Mask" "F.Paste")
			(net "LED_D2_R2")
		)
	)
	(footprint ""
		(layer "F.Cu")
		(at 275.3614 -64.897)
		(property "Reference" "R358"
			(at 0 0 0)
			(layer "F.SilkS")
			(hide yes)
			(effects
				(font
					(size 1.27 1.27)
				)
			)
		)
		(property "Value" ""
			(at 0 0 0)
			(layer "F.Fab")
			(effects
				(font
					(size 1.27 1.27)
				)
			)
		)
		(duplicate_pad_numbers_are_jumpers no)
		(fp_line
			(start -0.7874 -0.4064)
			(end 0.7874 -0.4064)
			(stroke
				(width 0.1524)
				(type default)
			)
			(layer "F.SilkS")
		)
		(fp_line
			(start -0.7874 0.4064)
			(end -0.7874 -0.4064)
			(stroke
				(width 0.1524)
				(type default)
			)
			(layer "F.SilkS")
		)
		(fp_line
			(start 0.7874 -0.4064)
			(end 0.7874 0.4064)
			(stroke
				(width 0.1524)
				(type default)
			)
			(layer "F.SilkS")
		)
		(fp_line
			(start 0.7874 0.4064)
			(end -0.7874 0.4064)
			(stroke
				(width 0.1524)
				(type default)
			)
			(layer "F.SilkS")
		)
		(fp_line
			(start -0.67945 -0.305054)
			(end -0.12065 -0.305054)
			(stroke
				(width 0.1)
				(type default)
			)
			(layer "F.Fab")
		)
		(fp_line
			(start -0.67945 0.3048)
			(end -0.67945 -0.305054)
			(stroke
				(width 0.1)
				(type default)
			)
			(layer "F.Fab")
		)
		(fp_line
			(start -0.12065 -0.305054)
			(end -0.12065 -0.2794)
			(stroke
				(width 0.1)
				(type default)
			)
			(layer "F.Fab")
		)
		(fp_line
			(start -0.12065 -0.2794)
			(end 0.12065 -0.2794)
			(stroke
				(width 0.1)
				(type default)
			)
			(layer "F.Fab")
		)
		(fp_line
			(start -0.12065 0.2794)
			(end -0.12065 0.3048)
			(stroke
				(width 0.1)
				(type default)
			)
			(layer "F.Fab")
		)
		(fp_line
			(start -0.12065 0.3048)
			(end -0.67945 0.3048)
			(stroke
				(width 0.1)
				(type default)
			)
			(layer "F.Fab")
		)
		(fp_line
			(start 0.120396 0.2794)
			(end -0.12065 0.2794)
			(stroke
				(width 0.1)
				(type default)
			)
			(layer "F.Fab")
		)
		(fp_line
			(start 0.120396 0.3048)
			(end 0.120396 0.2794)
			(stroke
				(width 0.1)
				(type default)
			)
			(layer "F.Fab")
		)
		(fp_line
			(start 0.12065 -0.3048)
			(end 0.67945 -0.3048)
			(stroke
				(width 0.1)
				(type default)
			)
			(layer "F.Fab")
		)
		(fp_line
			(start 0.12065 -0.2794)
			(end 0.12065 -0.3048)
			(stroke
				(width 0.1)
				(type default)
			)
			(layer "F.Fab")
		)
		(fp_line
			(start 0.67945 -0.3048)
			(end 0.67945 0.3048)
			(stroke
				(width 0.1)
				(type default)
			)
			(layer "F.Fab")
		)
		(fp_line
			(start 0.67945 0.3048)
			(end 0.120396 0.3048)
			(stroke
				(width 0.1)
				(type default)
			)
			(layer "F.Fab")
		)
		(pad "1" smd circle
			(at -0.40005 0)
			(size 0 0)
			(layers "F.Cu" "F.Mask" "F.Paste")
			(net "P52V_HS1_GPO1")
		)
		(pad "2" smd circle
			(at 0.40005 0)
			(size 0 0)
			(layers "F.Cu" "F.Mask" "F.Paste")
			(net "P52V_HS1_FLT")
		)
	)
)
